(kicad_pcb
	(version 20260206)
	(generator "pcbnew")
	(generator_version "10.0")
	(general
		(thickness 1.6)
		(legacy_teardrops no)
	)
	(paper "A4")
	(title_block
		(title "Bryce Canyon_IOM_IOC_16318-2_OCP.brd")
		(comment 1 "Bryce Canyon / footprints 926-933 of 1605")
	)
	(layers
		(0 "F.Cu" signal "TOP")
		(4 "In1.Cu" signal "L2GND")
		(6 "In2.Cu" signal "L3")
		(8 "In3.Cu" signal "L4VCC")
		(10 "In4.Cu" signal "L5VCC")
		(12 "In5.Cu" signal "L6")
		(14 "In6.Cu" signal "L7GND")
		(2 "B.Cu" signal "BOTTOM")
		(9 "F.Adhes" user "F.Adhesive")
		(11 "B.Adhes" user "B.Adhesive")
		(13 "F.Paste" user "Package Geometry/Pastemask Top")
		(15 "B.Paste" user "Package Geometry/Pastemask Bottom")
		(5 "F.SilkS" user "Ref Des/Silkscreen Top")
		(7 "B.SilkS" user "Ref Des/Silkscreen Bottom")
		(1 "F.Mask" user "Board Geometry/Soldermask Top")
		(3 "B.Mask" user "Board Geometry/Soldermask Bottom")
		(17 "Dwgs.User" user "User.Drawings")
		(19 "Cmts.User" user "User.Comments")
		(21 "Eco1.User" user "User.Eco1")
		(23 "Eco2.User" user "User.Eco2")
		(25 "Edge.Cuts" user "Board Geometry/Outline")
		(27 "Margin" user)
		(31 "F.CrtYd" user "Package Geometry/Place Bound Top")
		(29 "B.CrtYd" user "Package Geometry/Place Bound Bottom")
		(35 "F.Fab" user "Ref Des/Assembly Top")
		(33 "B.Fab" user "Ref Des/Assembly Bottom")
	)
	(footprint ""
		(layer "F.Cu")
		(at 10.771124 -135.285988 90)
		(property "Reference" "R224"
			(at 0 0 90)
			(layer "F.SilkS")
			(hide yes)
			(effects
				(font
					(size 1.27 1.27)
				)
			)
		)
		(property "Value" "4K7R2F-GP"
			(at 0.064008 -3.993896 90)
			(unlocked yes)
			(layer "F.Fab")
			(hide yes)
			(effects
				(font
					(size 1.016 1.016)
					(thickness 0.1524)
				)
			)
		)
		(property "Device Type" "R402H16"
			(at 0.064008 -5.517896 90)
			(unlocked yes)
			(layer "F.Fab")
			(hide yes)
			(effects
				(font
					(size 1.016 1.016)
					(thickness 0.1524)
				)
			)
		)
		(duplicate_pad_numbers_are_jumpers no)
		(fp_line
			(start 0.508 -0.9398)
			(end -0.508 -0.9398)
			(stroke
				(width 0.1524)
				(type default)
			)
			(layer "F.SilkS")
		)
		(fp_line
			(start -0.508 -0.9398)
			(end -0.508 0.9398)
			(stroke
				(width 0.1524)
				(type default)
			)
			(layer "F.SilkS")
		)
		(fp_rect
			(start -0.508 0.9398)
			(end 0.508 -0.9398)
			(stroke
				(width 0)
				(type default)
			)
			(fill no)
			(layer "F.CrtYd")
		)
		(fp_rect
			(start -0.508 0.9398)
			(end 0.508 -0.9398)
			(stroke
				(width 0)
				(type default)
			)
			(fill no)
			(layer "F.Fab")
		)
		(pad "1" smd custom
			(at 0 -0.4445 90)
			(size 0.1397 0.1397)
			(layers "F.Cu" "F.Mask" "F.Paste")
			(net "MEM_PAR")
			(options
				(clearance outline)
				(anchor circle)
			)
			(primitives
				(gr_poly
					(pts
						(arc
							(start -0.1778 -0.2794)
							(mid -0.249642 -0.249642)
							(end -0.2794 -0.1778)
						)
						(arc
							(start -0.2794 0.1778)
							(mid -0.249642 0.249642)
							(end -0.1778 0.2794)
						)
						(arc
							(start 0.1778 0.2794)
							(mid 0.249642 0.249642)
							(end 0.2794 0.1778)
						)
						(arc
							(start 0.2794 -0.1778)
							(mid 0.249642 -0.249642)
							(end 0.1778 -0.2794)
						)
					)
					(width 0)
					(fill yes)
				)
			)
		)
		(pad "2" smd custom
			(at 0 0.4445 90)
			(size 0.1397 0.1397)
			(layers "F.Cu" "F.Mask" "F.Paste")
			(net "P1V2_STBY")
			(options
				(clearance outline)
				(anchor circle)
			)
			(primitives
				(gr_poly
					(pts
						(arc
							(start -0.1778 -0.2794)
							(mid -0.249642 -0.249642)
							(end -0.2794 -0.1778)
						)
						(arc
							(start -0.2794 0.1778)
							(mid -0.249642 0.249642)
							(end -0.1778 0.2794)
						)
						(arc
							(start 0.1778 0.2794)
							(mid 0.249642 0.249642)
							(end 0.2794 0.1778)
						)
						(arc
							(start 0.2794 -0.1778)
							(mid 0.249642 -0.249642)
							(end 0.1778 -0.2794)
						)
					)
					(width 0)
					(fill yes)
				)
			)
		)
	)
	(footprint ""
		(layer "F.Cu")
		(at 174.560738 -71.55942 90)
		(property "Reference" "R587"
			(at 0 0 90)
			(layer "F.SilkS")
			(hide yes)
			(effects
				(font
					(size 1.27 1.27)
				)
			)
		)
		(property "Value" "2K2R2F-GP"
			(at 0.064008 -3.993896 90)
			(unlocked yes)
			(layer "F.Fab")
			(hide yes)
			(effects
				(font
					(size 1.016 1.016)
					(thickness 0.1524)
				)
			)
		)
		(property "Device Type" "R402H16"
			(at 0.064008 -5.517896 90)
			(unlocked yes)
			(layer "F.Fab")
			(hide yes)
			(effects
				(font
					(size 1.016 1.016)
					(thickness 0.1524)
				)
			)
		)
		(duplicate_pad_numbers_are_jumpers no)
		(fp_line
			(start 0.508 -0.9398)
			(end -0.508 -0.9398)
			(stroke
				(width 0.1524)
				(type default)
			)
			(layer "F.SilkS")
		)
		(fp_line
			(start -0.508 -0.9398)
			(end -0.508 0.9398)
			(stroke
				(width 0.1524)
				(type default)
			)
			(layer "F.SilkS")
		)
		(fp_rect
			(start -0.508 0.9398)
			(end 0.508 -0.9398)
			(stroke
				(width 0)
				(type default)
			)
			(fill no)
			(layer "F.CrtYd")
		)
		(fp_rect
			(start -0.508 0.9398)
			(end 0.508 -0.9398)
			(stroke
				(width 0)
				(type default)
			)
			(fill no)
			(layer "F.Fab")
		)
		(pad "1" smd custom
			(at 0 -0.4445 90)
			(size 0.1397 0.1397)
			(layers "F.Cu" "F.Mask" "F.Paste")
			(net "P1V8")
			(options
				(clearance outline)
				(anchor circle)
			)
			(primitives
				(gr_poly
					(pts
						(arc
							(start -0.1778 -0.2794)
							(mid -0.249642 -0.249642)
							(end -0.2794 -0.1778)
						)
						(arc
							(start -0.2794 0.1778)
							(mid -0.249642 0.249642)
							(end -0.1778 0.2794)
						)
						(arc
							(start 0.1778 0.2794)
							(mid 0.249642 0.249642)
							(end 0.2794 0.1778)
						)
						(arc
							(start 0.2794 -0.1778)
							(mid 0.249642 -0.249642)
							(end 0.1778 -0.2794)
						)
					)
					(width 0)
					(fill yes)
				)
			)
		)
		(pad "2" smd custom
			(at 0 0.4445 90)
			(size 0.1397 0.1397)
			(layers "F.Cu" "F.Mask" "F.Paste")
			(net "IOC_SDA_4")
			(options
				(clearance outline)
				(anchor circle)
			)
			(primitives
				(gr_poly
					(pts
						(arc
							(start -0.1778 -0.2794)
							(mid -0.249642 -0.249642)
							(end -0.2794 -0.1778)
						)
						(arc
							(start -0.2794 0.1778)
							(mid -0.249642 0.249642)
							(end -0.1778 0.2794)
						)
						(arc
							(start 0.1778 0.2794)
							(mid 0.249642 0.249642)
							(end 0.2794 0.1778)
						)
						(arc
							(start 0.2794 -0.1778)
							(mid 0.249642 -0.249642)
							(end 0.1778 -0.2794)
						)
					)
					(width 0)
					(fill yes)
				)
			)
		)
	)
	(footprint ""
		(layer "F.Cu")
		(at 28.194 -155.702 -90)
		(property "Reference" "R772"
			(at 0 0 270)
			(layer "F.SilkS")
			(hide yes)
			(effects
				(font
					(size 1.27 1.27)
				)
			)
		)
		(property "Value" "0R2J-2-GP"
			(at 0.064008 -3.993896 270)
			(unlocked yes)
			(layer "F.Fab")
			(hide yes)
			(effects
				(font
					(size 1.016 1.016)
					(thickness 0.1524)
				)
			)
		)
		(property "Device Type" "R402H16"
			(at 0.064008 -5.517896 270)
			(unlocked yes)
			(layer "F.Fab")
			(hide yes)
			(effects
				(font
					(size 1.016 1.016)
					(thickness 0.1524)
				)
			)
		)
		(duplicate_pad_numbers_are_jumpers no)
		(fp_line
			(start -0.508 -0.9398)
			(end -0.508 0.9398)
			(stroke
				(width 0.1524)
				(type default)
			)
			(layer "F.SilkS")
		)
		(fp_line
			(start 0.508 -0.9398)
			(end -0.508 -0.9398)
			(stroke
				(width 0.1524)
				(type default)
			)
			(layer "F.SilkS")
		)
		(fp_rect
			(start -0.508 0.9398)
			(end 0.508 -0.9398)
			(stroke
				(width 0)
				(type default)
			)
			(fill no)
			(layer "F.CrtYd")
		)
		(fp_rect
			(start -0.508 0.9398)
			(end 0.508 -0.9398)
			(stroke
				(width 0)
				(type default)
			)
			(fill no)
			(layer "F.Fab")
		)
		(pad "1" smd custom
			(at 0 -0.4445 270)
			(size 0.1397 0.1397)
			(layers "F.Cu" "F.Mask" "F.Paste")
			(net "DEBUG_GPIO_BMC_R_5")
			(options
				(clearance outline)
				(anchor circle)
			)
			(primitives
				(gr_poly
					(pts
						(arc
							(start -0.1778 -0.2794)
							(mid -0.249642 -0.249642)
							(end -0.2794 -0.1778)
						)
						(arc
							(start -0.2794 0.1778)
							(mid -0.249642 0.249642)
							(end -0.1778 0.2794)
						)
						(arc
							(start 0.1778 0.2794)
							(mid 0.249642 0.249642)
							(end 0.2794 0.1778)
						)
						(arc
							(start 0.2794 -0.1778)
							(mid 0.249642 -0.249642)
							(end 0.1778 -0.2794)
						)
					)
					(width 0)
					(fill yes)
				)
			)
		)
		(pad "2" smd custom
			(at 0 0.4445 270)
			(size 0.1397 0.1397)
			(layers "F.Cu" "F.Mask" "F.Paste")
			(net "DEBUG_GPIO_BMC_5")
			(options
				(clearance outline)
				(anchor circle)
			)
			(primitives
				(gr_poly
					(pts
						(arc
							(start -0.1778 -0.2794)
							(mid -0.249642 -0.249642)
							(end -0.2794 -0.1778)
						)
						(arc
							(start -0.2794 0.1778)
							(mid -0.249642 0.249642)
							(end -0.1778 0.2794)
						)
						(arc
							(start 0.1778 0.2794)
							(mid 0.249642 0.249642)
							(end 0.2794 0.1778)
						)
						(arc
							(start 0.2794 -0.1778)
							(mid 0.249642 -0.249642)
							(end 0.1778 -0.2794)
						)
					)
					(width 0)
					(fill yes)
				)
			)
		)
	)
	(footprint ""
		(layer "F.Cu")
		(at 27.5844 -145.3515)
		(property "Reference" "R219"
			(at 0 0 0)
			(layer "F.SilkS")
			(hide yes)
			(effects
				(font
					(size 1.27 1.27)
				)
			)
		)
		(property "Value" "240R2F-1-GP"
			(at 0.064008 -3.993896 0)
			(unlocked yes)
			(layer "F.Fab")
			(hide yes)
			(effects
				(font
					(size 1.016 1.016)
					(thickness 0.1524)
				)
			)
		)
		(property "Device Type" "R402H16"
			(at 0.064008 -5.517896 0)
			(unlocked yes)
			(layer "F.Fab")
			(hide yes)
			(effects
				(font
					(size 1.016 1.016)
					(thickness 0.1524)
				)
			)
		)
		(duplicate_pad_numbers_are_jumpers no)
		(fp_line
			(start -0.508 -0.9398)
			(end -0.508 0.9398)
			(stroke
				(width 0.1524)
				(type default)
			)
			(layer "F.SilkS")
		)
		(fp_line
			(start 0.508 -0.9398)
			(end -0.508 -0.9398)
			(stroke
				(width 0.1524)
				(type default)
			)
			(layer "F.SilkS")
		)
		(fp_rect
			(start -0.508 0.9398)
			(end 0.508 -0.9398)
			(stroke
				(width 0)
				(type default)
			)
			(fill no)
			(layer "F.CrtYd")
		)
		(fp_rect
			(start -0.508 0.9398)
			(end 0.508 -0.9398)
			(stroke
				(width 0)
				(type default)
			)
			(fill no)
			(layer "F.Fab")
		)
		(pad "1" smd custom
			(at 0 -0.4445)
			(size 0.1397 0.1397)
			(layers "F.Cu" "F.Mask" "F.Paste")
			(net "GND")
			(options
				(clearance outline)
				(anchor circle)
			)
			(primitives
				(gr_poly
					(pts
						(arc
							(start -0.1778 -0.2794)
							(mid -0.249642 -0.249642)
							(end -0.2794 -0.1778)
						)
						(arc
							(start -0.2794 0.1778)
							(mid -0.249642 0.249642)
							(end -0.1778 0.2794)
						)
						(arc
							(start 0.1778 0.2794)
							(mid 0.249642 0.249642)
							(end 0.2794 0.1778)
						)
						(arc
							(start 0.2794 -0.1778)
							(mid 0.249642 -0.249642)
							(end 0.1778 -0.2794)
						)
					)
					(width 0)
					(fill yes)
				)
			)
		)
		(pad "2" smd custom
			(at 0 0.4445)
			(size 0.1397 0.1397)
			(layers "F.Cu" "F.Mask" "F.Paste")
			(net "PD_ZQ")
			(options
				(clearance outline)
				(anchor circle)
			)
			(primitives
				(gr_poly
					(pts
						(arc
							(start -0.1778 -0.2794)
							(mid -0.249642 -0.249642)
							(end -0.2794 -0.1778)
						)
						(arc
							(start -0.2794 0.1778)
							(mid -0.249642 0.249642)
							(end -0.1778 0.2794)
						)
						(arc
							(start 0.1778 0.2794)
							(mid 0.249642 0.249642)
							(end 0.2794 0.1778)
						)
						(arc
							(start 0.2794 -0.1778)
							(mid 0.249642 -0.249642)
							(end 0.1778 -0.2794)
						)
					)
					(width 0)
					(fill yes)
				)
			)
		)
	)
	(footprint ""
		(layer "F.Cu")
		(at 69.5452 -181.6354 -90)
		(property "Reference" "C201"
			(at 0 0 270)
			(layer "F.SilkS")
			(hide yes)
			(effects
				(font
					(size 1.27 1.27)
				)
			)
		)
		(property "Value" "SCD1U16V2KX-3GP"
			(at 1.1811 -2.7051 270)
			(unlocked yes)
			(layer "F.Fab")
			(hide yes)
			(effects
				(font
					(size 1.016 1.016)
					(thickness 0.1524)
				)
			)
		)
		(property "Device Type" "C402H22"
			(at 1.1811 -4.2291 270)
			(unlocked yes)
			(layer "F.Fab")
			(hide yes)
			(effects
				(font
					(size 1.016 1.016)
					(thickness 0.1524)
				)
			)
		)
		(duplicate_pad_numbers_are_jumpers no)
		(fp_rect
			(start -0.4318 0.9525)
			(end 0.4318 -0.9525)
			(stroke
				(width 0)
				(type default)
			)
			(fill no)
			(layer "F.CrtYd")
		)
		(fp_rect
			(start -0.4318 0.9525)
			(end 0.4318 -0.9525)
			(stroke
				(width 0)
				(type default)
			)
			(fill no)
			(layer "F.Fab")
		)
		(pad "1" smd custom
			(at 0 -0.4445 270)
			(size 0.1524 0.1524)
			(layers "F.Cu" "F.Mask" "F.Paste")
			(net "TPS74801_P2V5_STBY_EN")
			(options
				(clearance outline)
				(anchor circle)
			)
			(primitives
				(gr_poly
					(pts
						(arc
							(start 0.3048 -0.2032)
							(mid 0.275042 -0.275042)
							(end 0.2032 -0.3048)
						)
						(arc
							(start -0.2032 -0.3048)
							(mid -0.275042 -0.275042)
							(end -0.3048 -0.2032)
						)
						(arc
							(start -0.3048 0.2032)
							(mid -0.275042 0.275042)
							(end -0.2032 0.3048)
						)
						(arc
							(start 0.2032 0.3048)
							(mid 0.275042 0.275042)
							(end 0.3048 0.2032)
						)
					)
					(width 0)
					(fill yes)
				)
			)
		)
		(pad "2" smd custom
			(at 0 0.4445 270)
			(size 0.1524 0.1524)
			(layers "F.Cu" "F.Mask" "F.Paste")
			(net "GND")
			(options
				(clearance outline)
				(anchor circle)
			)
			(primitives
				(gr_poly
					(pts
						(arc
							(start 0.3048 -0.2032)
							(mid 0.275042 -0.275042)
							(end 0.2032 -0.3048)
						)
						(arc
							(start -0.2032 -0.3048)
							(mid -0.275042 -0.275042)
							(end -0.3048 -0.2032)
						)
						(arc
							(start -0.3048 0.2032)
							(mid -0.275042 0.275042)
							(end -0.2032 0.3048)
						)
						(arc
							(start 0.2032 0.3048)
							(mid 0.275042 0.275042)
							(end 0.3048 0.2032)
						)
					)
					(width 0)
					(fill yes)
				)
			)
		)
	)
	(footprint ""
		(layer "F.Cu")
		(at 147.85086 -13.12672)
		(property "Reference" "R737"
			(at 0 0 0)
			(layer "F.SilkS")
			(hide yes)
			(effects
				(font
					(size 1.27 1.27)
				)
			)
		)
		(property "Value" "120R3F-L-GP"
			(at -0.0254 -2.5146 0)
			(unlocked yes)
			(layer "F.Fab")
			(hide yes)
			(effects
				(font
					(size 1.016 1.016)
					(thickness 0.1524)
				)
			)
		)
		(property "Device Type" "R603H22"
			(at -0.0254 -4.0386 0)
			(unlocked yes)
			(layer "F.Fab")
			(hide yes)
			(effects
				(font
					(size 1.016 1.016)
					(thickness 0.1524)
				)
			)
		)
		(duplicate_pad_numbers_are_jumpers no)
		(fp_line
			(start -0.4826 0)
			(end -0.2032 0)
			(stroke
				(width 0.2032)
				(type default)
			)
			(layer "F.SilkS")
		)
		(fp_line
			(start 0.2032 0)
			(end 0.4826 0)
			(stroke
				(width 0.2032)
				(type default)
			)
			(layer "F.SilkS")
		)
		(fp_rect
			(start -0.5842 1.3335)
			(end 0.5842 -1.3335)
			(stroke
				(width 0)
				(type default)
			)
			(fill no)
			(layer "F.CrtYd")
		)
		(fp_rect
			(start -0.5842 1.3335)
			(end 0.5842 -1.3335)
			(stroke
				(width 0)
				(type default)
			)
			(fill no)
			(layer "F.Fab")
		)
		(pad "1" smd custom
			(at 0 -0.762)
			(size 0.2159 0.2159)
			(layers "F.Cu" "F.Mask" "F.Paste")
			(net "EXT2_LED_YELLOW_D1")
			(options
				(clearance outline)
				(anchor circle)
			)
			(primitives
				(gr_poly
					(pts
						(arc
							(start -0.3302 -0.4318)
							(mid -0.402042 -0.402042)
							(end -0.4318 -0.3302)
						)
						(arc
							(start -0.4318 0.3302)
							(mid -0.402042 0.402042)
							(end -0.3302 0.4318)
						)
						(arc
							(start 0.3302 0.4318)
							(mid 0.402042 0.402042)
							(end 0.4318 0.3302)
						)
						(arc
							(start 0.4318 -0.3302)
							(mid 0.402042 -0.402042)
							(end 0.3302 -0.4318)
						)
					)
					(width 0)
					(fill yes)
				)
			)
		)
		(pad "2" smd custom
			(at 0 0.762)
			(size 0.2159 0.2159)
			(layers "F.Cu" "F.Mask" "F.Paste")
			(net "EXT2_LED_YELLOW")
			(options
				(clearance outline)
				(anchor circle)
			)
			(primitives
				(gr_poly
					(pts
						(arc
							(start -0.3302 -0.4318)
							(mid -0.402042 -0.402042)
							(end -0.4318 -0.3302)
						)
						(arc
							(start -0.4318 0.3302)
							(mid -0.402042 0.402042)
							(end -0.3302 0.4318)
						)
						(arc
							(start 0.3302 0.4318)
							(mid 0.402042 0.402042)
							(end 0.4318 0.3302)
						)
						(arc
							(start 0.4318 -0.3302)
							(mid 0.402042 -0.402042)
							(end 0.3302 -0.4318)
						)
					)
					(width 0)
					(fill yes)
				)
			)
		)
	)
	(footprint ""
		(layer "F.Cu")
		(at 187.54471 -90.86469)
		(property "Reference" "R643"
			(at 0 0 0)
			(layer "F.SilkS")
			(hide yes)
			(effects
				(font
					(size 1.27 1.27)
				)
			)
		)
		(property "Value" "4K7R2F-GP"
			(at 0.064008 -3.993896 0)
			(unlocked yes)
			(layer "F.Fab")
			(hide yes)
			(effects
				(font
					(size 1.016 1.016)
					(thickness 0.1524)
				)
			)
		)
		(property "Device Type" "R402H16"
			(at 0.064008 -5.517896 0)
			(unlocked yes)
			(layer "F.Fab")
			(hide yes)
			(effects
				(font
					(size 1.016 1.016)
					(thickness 0.1524)
				)
			)
		)
		(duplicate_pad_numbers_are_jumpers no)
		(fp_line
			(start -0.508 -0.9398)
			(end -0.508 0.9398)
			(stroke
				(width 0.1524)
				(type default)
			)
			(layer "F.SilkS")
		)
		(fp_line
			(start 0.508 -0.9398)
			(end -0.508 -0.9398)
			(stroke
				(width 0.1524)
				(type default)
			)
			(layer "F.SilkS")
		)
		(fp_rect
			(start -0.508 0.9398)
			(end 0.508 -0.9398)
			(stroke
				(width 0)
				(type default)
			)
			(fill no)
			(layer "F.CrtYd")
		)
		(fp_rect
			(start -0.508 0.9398)
			(end 0.508 -0.9398)
			(stroke
				(width 0)
				(type default)
			)
			(fill no)
			(layer "F.Fab")
		)
		(pad "1" smd custom
			(at 0 -0.4445)
			(size 0.1397 0.1397)
			(layers "F.Cu" "F.Mask" "F.Paste")
			(net "P1V8")
			(options
				(clearance outline)
				(anchor circle)
			)
			(primitives
				(gr_poly
					(pts
						(arc
							(start -0.1778 -0.2794)
							(mid -0.249642 -0.249642)
							(end -0.2794 -0.1778)
						)
						(arc
							(start -0.2794 0.1778)
							(mid -0.249642 0.249642)
							(end -0.1778 0.2794)
						)
						(arc
							(start 0.1778 0.2794)
							(mid 0.249642 0.249642)
							(end 0.2794 0.1778)
						)
						(arc
							(start 0.2794 -0.1778)
							(mid 0.249642 -0.249642)
							(end 0.1778 -0.2794)
						)
					)
					(width 0)
					(fill yes)
				)
			)
		)
		(pad "2" smd custom
			(at 0 0.4445)
			(size 0.1397 0.1397)
			(layers "F.Cu" "F.Mask" "F.Paste")
			(net "SYS_DBMODE1")
			(options
				(clearance outline)
				(anchor circle)
			)
			(primitives
				(gr_poly
					(pts
						(arc
							(start -0.1778 -0.2794)
							(mid -0.249642 -0.249642)
							(end -0.2794 -0.1778)
						)
						(arc
							(start -0.2794 0.1778)
							(mid -0.249642 0.249642)
							(end -0.1778 0.2794)
						)
						(arc
							(start 0.1778 0.2794)
							(mid 0.249642 0.249642)
							(end 0.2794 0.1778)
						)
						(arc
							(start 0.2794 -0.1778)
							(mid 0.249642 -0.249642)
							(end 0.1778 -0.2794)
						)
					)
					(width 0)
					(fill yes)
				)
			)
		)
	)
	(footprint ""
		(layer "F.Cu")
		(at 184.1754 -114.0714 90)
		(property "Reference" "C272"
			(at 0 0 90)
			(layer "F.SilkS")
			(hide yes)
			(effects
				(font
					(size 1.27 1.27)
				)
			)
		)
		(property "Value" "SC10U16V5KX-7-GP-U"
			(at -0.0762 -6.1214 90)
			(unlocked yes)
			(layer "F.Fab")
			(hide yes)
			(effects
				(font
					(size 1.016 1.016)
					(thickness 0.1524)
				)
			)
		)
		(property "Device Type" "C805H58"
			(at -0.0762 -8.1534 90)
			(unlocked yes)
			(layer "F.Fab")
			(hide yes)
			(effects
				(font
					(size 1.016 1.016)
					(thickness 0.1524)
				)
			)
		)
		(duplicate_pad_numbers_are_jumpers no)
		(fp_line
			(start 0.635 0)
			(end -0.635 0)
			(stroke
				(width 0.508)
				(type default)
			)
			(layer "F.SilkS")
		)
		(fp_rect
			(start -0.9652 1.778)
			(end 0.9652 -1.778)
			(stroke
				(width 0)
				(type default)
			)
			(fill no)
			(layer "F.CrtYd")
		)
		(fp_poly
			(pts
				(xy -0.9652 -1.778) (xy 0.9652 -1.778) (xy 0.9652 1.778) (xy -0.9652 1.778)
			)
			(stroke
				(width 0)
				(type default)
			)
			(fill no)
			(layer "F.Fab")
		)
		(pad "1" smd rect
			(at 0 -0.9652 90)
			(size 1.397 1.143)
			(layers "F.Cu" "F.Mask" "F.Paste")
			(net "VT235_VDDH")
		)
		(pad "2" smd rect
			(at 0 0.9652 90)
			(size 1.397 1.143)
			(layers "F.Cu" "F.Mask" "F.Paste")
			(net "GND")
		)
	)
)
